FILE_TYPE = MACRO_DRAWING;
SET COLOR_WIRE YELLOW;
SET COLOR_PROP ORANGE;
SET COLOR_DOT WHITE;
SET COLOR_ARC YELLOW;
SET COLOR_BODY GREEN;
SET COLOR_NOTE PURPLE;
SET PROP_DISPLAY VALUE;
SET PAGE_NUMBER P134;
FORCEADD QUANTA_TITLE_BLOCK_C..1
(0 0);
FORCEPROP 1 LAST CUSTOM_TXT_CDS <NAME_2>
J 0
(-3175 50);
FORCEPROP 1 LAST CUSTOM_TXT_CDS <NAME_1>
J 0
(-3175 175);
FORCEPROP 1 LAST CUSTOM_TXT_CDS <Q_NUMBER>
J 0
(-1403 103);
DISPLAY 1.212766 (-1403 103);
FORCEPROP 1 LAST CUSTOM_TXT_CDS <Q_PROJ>
J 0
(-2382 102);
DISPLAY 1.212766 (-2382 102);
FORCEPROP 1 LAST CUSTOM_TXT_CDS <Q_REV>
J 0
(-184 103);
DISPLAY 1.212766 (-184 103);
FORCEPROP 1 LAST CUSTOM_TXT_CDS <CON_LAST_MODIFIED>
J 0
(-1885 15);
DISPLAY 0.978723 (-1885 15);
FORCEPROP 1 LAST CUSTOM_TXT_CDS <CON_PAGE_NUM> OF <CON_TOTAL_PAGES>
J 0
(-446 18);
DISPLAY 0.978723 (-446 18);
FORCEPROP 1 LAST Q_DEPT BU9
J 1
(-3763 49);
DISPLAY 1.957447 (-3763 49);
PAINT GREEN (-3763 49);
FORCEPROP 1 LAST Q_TITLE TEMP SENSOR
J 0
(-9275 75);
DISPLAY 2.446809 (-9275 75);
PAINT GREEN (-9275 75);
FORCEPROP 2 LAST PAGE_BORDER TRUE
J 0
(-7890 5250);
DISPLAY 0.638298 (-7890 5250);
PAINT PINK (-7890 5250);
DISPLAY INVISIBLE (-7890 5250);
FORCEPROP 2 LAST CDS_LIB pure_quanta
J 0
(0 0);
DISPLAY INVISIBLE (0 0);
FORCEPROP 1 LAST CDS_LMAN_SYM_OUTLINE -9475,6775,100,-125
J 0
(0 0);
DISPLAY 0.468085 (0 0);
PAINT GREEN (0 0);
DISPLAY INVISIBLE (0 0);
FORCEPROP 1 LAST COMMENT_BODY TRUE
J 0
(12 -13);
DISPLAY 0.978723 (12 -13);
PAINT GREEN (12 -13);
DISPLAY INVISIBLE (12 -13);
FORCEPROP 2 LAST CDS_XR_PAGE_TITLE CR-134 : @T6G_MB_LIB.T6G(SCH_1):PAGE134
J 0
(-7890 5250);
DISPLAY 0.638298 (-7890 5250);
PAINT PINK (-7890 5250);
DISPLAY INVISIBLE (-7890 5250);
FORCEPROP 2 LAST CUSTOM_TXT_CDS <XR_PAGE_TITLE>
J 0
(-7890 5250);
DISPLAY 0.638298 (-7890 5250);
PAINT PINK (-7890 5250);
DISPLAY INVISIBLE (-7890 5250);
FORCEPROP 0 LAST CDS_CON_LAST_MODIFIED Wed Mar 09 18:58:06 2022
J 0
(-1885 15);
DISPLAY INVISIBLE (-1885 15);
QUIT
